(kicad_pcb
	(version 20260206)
	(generator "pcbnew")
	(generator_version "10.0")
	(general
		(thickness 1.6)
		(legacy_teardrops no)
	)
	(paper "A4")
	(title_block
		(title "01162023_DA0F0TEBIF0_F0T_Expander_BD_F_brd_V02_OCP.brd")
		(comment 1 "Grand Teton / footprints 5722-5728 of 9728")
	)
	(layers
		(0 "F.Cu" signal "TOP")
		(4 "In1.Cu" signal "GND")
		(6 "In2.Cu" signal "VCC")
		(8 "In3.Cu" signal "VCC1")
		(10 "In4.Cu" signal "GND1")
		(12 "In5.Cu" signal "IN1")
		(14 "In6.Cu" signal "GND2")
		(16 "In7.Cu" signal "IN2")
		(18 "In8.Cu" signal "GND3")
		(20 "In9.Cu" signal "IN3")
		(22 "In10.Cu" signal "GND4")
		(24 "In11.Cu" signal "IN4")
		(26 "In12.Cu" signal "GND5")
		(28 "In13.Cu" signal "IN5")
		(30 "In14.Cu" signal "GND6")
		(32 "In15.Cu" signal "IN6")
		(34 "In16.Cu" signal "GND7")
		(2 "B.Cu" signal "BOTTOM")
		(9 "F.Adhes" user "F.Adhesive")
		(11 "B.Adhes" user "B.Adhesive")
		(13 "F.Paste" user "Package Geometry/Pastemask Top")
		(15 "B.Paste" user "Package Geometry/Pastemask Bottom")
		(5 "F.SilkS" user "Ref Des/Silkscreen Top")
		(7 "B.SilkS" user "Ref Des/Silkscreen Bottom")
		(1 "F.Mask" user "Board Geometry/Soldermask Top")
		(3 "B.Mask" user "Board Geometry/Soldermask Bottom")
		(17 "Dwgs.User" user "User.Drawings")
		(19 "Cmts.User" user "User.Comments")
		(21 "Eco1.User" user "User.Eco1")
		(23 "Eco2.User" user "User.Eco2")
		(25 "Edge.Cuts" user "Board Geometry/Outline")
		(27 "Margin" user)
		(31 "F.CrtYd" user "Package Geometry/Place Bound Top")
		(29 "B.CrtYd" user "Package Geometry/Place Bound Bottom")
		(35 "F.Fab" user "Ref Des/Assembly Top")
		(33 "B.Fab" user "Ref Des/Assembly Bottom")
	)
	(footprint ""
		(layer "F.Cu")
		(at 78.267814 -53.051456)
		(property "Reference" "R4462"
			(at 0 0 0)
			(layer "F.SilkS")
			(hide yes)
			(effects
				(font
					(size 1.27 1.27)
				)
			)
		)
		(property "Value" ""
			(at 0 0 0)
			(layer "F.Fab")
			(effects
				(font
					(size 1.27 1.27)
				)
			)
		)
		(duplicate_pad_numbers_are_jumpers no)
		(fp_line
			(start -0.7874 -0.4064)
			(end 0.7874 -0.4064)
			(stroke
				(width 0.1524)
				(type default)
			)
			(layer "F.SilkS")
		)
		(fp_line
			(start -0.7874 0.4064)
			(end -0.7874 -0.4064)
			(stroke
				(width 0.1524)
				(type default)
			)
			(layer "F.SilkS")
		)
		(fp_line
			(start 0.7874 -0.4064)
			(end 0.7874 0.4064)
			(stroke
				(width 0.1524)
				(type default)
			)
			(layer "F.SilkS")
		)
		(fp_line
			(start 0.7874 0.4064)
			(end -0.7874 0.4064)
			(stroke
				(width 0.1524)
				(type default)
			)
			(layer "F.SilkS")
		)
		(fp_line
			(start -0.67945 -0.305054)
			(end -0.12065 -0.305054)
			(stroke
				(width 0.1)
				(type default)
			)
			(layer "F.Fab")
		)
		(fp_line
			(start -0.67945 0.3048)
			(end -0.67945 -0.305054)
			(stroke
				(width 0.1)
				(type default)
			)
			(layer "F.Fab")
		)
		(fp_line
			(start -0.12065 -0.305054)
			(end -0.12065 -0.2794)
			(stroke
				(width 0.1)
				(type default)
			)
			(layer "F.Fab")
		)
		(fp_line
			(start -0.12065 -0.2794)
			(end 0.12065 -0.2794)
			(stroke
				(width 0.1)
				(type default)
			)
			(layer "F.Fab")
		)
		(fp_line
			(start -0.12065 0.2794)
			(end -0.12065 0.3048)
			(stroke
				(width 0.1)
				(type default)
			)
			(layer "F.Fab")
		)
		(fp_line
			(start -0.12065 0.3048)
			(end -0.67945 0.3048)
			(stroke
				(width 0.1)
				(type default)
			)
			(layer "F.Fab")
		)
		(fp_line
			(start 0.120396 0.2794)
			(end -0.12065 0.2794)
			(stroke
				(width 0.1)
				(type default)
			)
			(layer "F.Fab")
		)
		(fp_line
			(start 0.120396 0.3048)
			(end 0.120396 0.2794)
			(stroke
				(width 0.1)
				(type default)
			)
			(layer "F.Fab")
		)
		(fp_line
			(start 0.12065 -0.3048)
			(end 0.67945 -0.3048)
			(stroke
				(width 0.1)
				(type default)
			)
			(layer "F.Fab")
		)
		(fp_line
			(start 0.12065 -0.2794)
			(end 0.12065 -0.3048)
			(stroke
				(width 0.1)
				(type default)
			)
			(layer "F.Fab")
		)
		(fp_line
			(start 0.67945 -0.3048)
			(end 0.67945 0.3048)
			(stroke
				(width 0.1)
				(type default)
			)
			(layer "F.Fab")
		)
		(fp_line
			(start 0.67945 0.3048)
			(end 0.120396 0.3048)
			(stroke
				(width 0.1)
				(type default)
			)
			(layer "F.Fab")
		)
		(pad "1" smd circle
			(at -0.40005 0)
			(size 0 0)
			(layers "F.Cu" "F.Mask" "F.Paste")
			(net "PWRGD_P12V_SSD2")
		)
		(pad "2" smd circle
			(at 0.40005 0)
			(size 0 0)
			(layers "F.Cu" "F.Mask" "F.Paste")
			(net "PWRGD_P12V_SSD2_R")
		)
	)
	(footprint ""
		(layer "F.Cu")
		(at 80.019398 -142.590266 180)
		(property "Reference" "C16"
			(at 0 0 180)
			(layer "F.SilkS")
			(hide yes)
			(effects
				(font
					(size 1.27 1.27)
				)
			)
		)
		(property "Value" ""
			(at 0 0 180)
			(layer "F.Fab")
			(effects
				(font
					(size 1.27 1.27)
				)
			)
		)
		(duplicate_pad_numbers_are_jumpers no)
		(fp_line
			(start 0.299974 0.150114)
			(end -0.299974 0.150114)
			(stroke
				(width 0.1)
				(type default)
			)
			(layer "F.Fab")
		)
		(fp_line
			(start 0.299974 -0.150114)
			(end 0.299974 0.150114)
			(stroke
				(width 0.1)
				(type default)
			)
			(layer "F.Fab")
		)
		(fp_line
			(start -0.299974 0.150114)
			(end -0.299974 -0.150114)
			(stroke
				(width 0.1)
				(type default)
			)
			(layer "F.Fab")
		)
		(fp_line
			(start -0.299974 -0.150114)
			(end 0.299974 -0.150114)
			(stroke
				(width 0.1)
				(type default)
			)
			(layer "F.Fab")
		)
		(pad "1" smd rect
			(at -0.2667 0 180)
			(size 0.3048 0.381)
			(layers "F.Cu" "F.Mask" "F.Paste")
			(net "P5E_PEX0_STN0_TX_DN<8>")
		)
		(pad "2" smd rect
			(at 0.2667 0 180)
			(size 0.3048 0.381)
			(layers "F.Cu" "F.Mask" "F.Paste")
			(net "P5E_PEX0_STN0_TX_C_DN<8>")
		)
	)
	(footprint ""
		(layer "F.Cu")
		(at 227.946458 -306.681632 -90)
		(property "Reference" "PR172"
			(at 0 0 270)
			(layer "F.SilkS")
			(hide yes)
			(effects
				(font
					(size 1.27 1.27)
				)
			)
		)
		(property "Value" ""
			(at 0 0 270)
			(layer "F.Fab")
			(effects
				(font
					(size 1.27 1.27)
				)
			)
		)
		(duplicate_pad_numbers_are_jumpers no)
		(fp_line
			(start -0.7874 0.4064)
			(end -0.7874 -0.4064)
			(stroke
				(width 0.1524)
				(type default)
			)
			(layer "F.SilkS")
		)
		(fp_line
			(start 0.7874 0.4064)
			(end -0.7874 0.4064)
			(stroke
				(width 0.1524)
				(type default)
			)
			(layer "F.SilkS")
		)
		(fp_line
			(start -0.7874 -0.4064)
			(end 0.7874 -0.4064)
			(stroke
				(width 0.1524)
				(type default)
			)
			(layer "F.SilkS")
		)
		(fp_line
			(start 0.7874 -0.4064)
			(end 0.7874 0.4064)
			(stroke
				(width 0.1524)
				(type default)
			)
			(layer "F.SilkS")
		)
		(fp_line
			(start -0.67945 0.3048)
			(end -0.67945 -0.305054)
			(stroke
				(width 0.1)
				(type default)
			)
			(layer "F.Fab")
		)
		(fp_line
			(start -0.12065 0.3048)
			(end -0.67945 0.3048)
			(stroke
				(width 0.1)
				(type default)
			)
			(layer "F.Fab")
		)
		(fp_line
			(start 0.120396 0.3048)
			(end 0.120396 0.2794)
			(stroke
				(width 0.1)
				(type default)
			)
			(layer "F.Fab")
		)
		(fp_line
			(start 0.67945 0.3048)
			(end 0.120396 0.3048)
			(stroke
				(width 0.1)
				(type default)
			)
			(layer "F.Fab")
		)
		(fp_line
			(start -0.12065 0.2794)
			(end -0.12065 0.3048)
			(stroke
				(width 0.1)
				(type default)
			)
			(layer "F.Fab")
		)
		(fp_line
			(start 0.120396 0.2794)
			(end -0.12065 0.2794)
			(stroke
				(width 0.1)
				(type default)
			)
			(layer "F.Fab")
		)
		(fp_line
			(start -0.12065 -0.2794)
			(end 0.12065 -0.2794)
			(stroke
				(width 0.1)
				(type default)
			)
			(layer "F.Fab")
		)
		(fp_line
			(start 0.12065 -0.2794)
			(end 0.12065 -0.3048)
			(stroke
				(width 0.1)
				(type default)
			)
			(layer "F.Fab")
		)
		(fp_line
			(start 0.12065 -0.3048)
			(end 0.67945 -0.3048)
			(stroke
				(width 0.1)
				(type default)
			)
			(layer "F.Fab")
		)
		(fp_line
			(start 0.67945 -0.3048)
			(end 0.67945 0.3048)
			(stroke
				(width 0.1)
				(type default)
			)
			(layer "F.Fab")
		)
		(fp_line
			(start -0.67945 -0.305054)
			(end -0.12065 -0.305054)
			(stroke
				(width 0.1)
				(type default)
			)
			(layer "F.Fab")
		)
		(fp_line
			(start -0.12065 -0.305054)
			(end -0.12065 -0.2794)
			(stroke
				(width 0.1)
				(type default)
			)
			(layer "F.Fab")
		)
		(pad "1" smd circle
			(at -0.40005 0 270)
			(size 0 0)
			(layers "F.Cu" "F.Mask" "F.Paste")
			(net "P1V25_PEX1_CS")
		)
		(pad "2" smd circle
			(at 0.40005 0 270)
			(size 0 0)
			(layers "F.Cu" "F.Mask" "F.Paste")
			(net "GND")
		)
	)
	(footprint ""
		(layer "F.Cu")
		(at 169.22623 -39.73576 -90)
		(property "Reference" "R5557"
			(at 0 0 270)
			(layer "F.SilkS")
			(hide yes)
			(effects
				(font
					(size 1.27 1.27)
				)
			)
		)
		(property "Value" ""
			(at 0 0 270)
			(layer "F.Fab")
			(effects
				(font
					(size 1.27 1.27)
				)
			)
		)
		(duplicate_pad_numbers_are_jumpers no)
		(fp_line
			(start -0.7874 0.4064)
			(end -0.7874 -0.4064)
			(stroke
				(width 0.1524)
				(type default)
			)
			(layer "F.SilkS")
		)
		(fp_line
			(start 0.7874 0.4064)
			(end -0.7874 0.4064)
			(stroke
				(width 0.1524)
				(type default)
			)
			(layer "F.SilkS")
		)
		(fp_line
			(start -0.7874 -0.4064)
			(end 0.7874 -0.4064)
			(stroke
				(width 0.1524)
				(type default)
			)
			(layer "F.SilkS")
		)
		(fp_line
			(start 0.7874 -0.4064)
			(end 0.7874 0.4064)
			(stroke
				(width 0.1524)
				(type default)
			)
			(layer "F.SilkS")
		)
		(fp_line
			(start -0.67945 0.3048)
			(end -0.67945 -0.305054)
			(stroke
				(width 0.1)
				(type default)
			)
			(layer "F.Fab")
		)
		(fp_line
			(start -0.12065 0.3048)
			(end -0.67945 0.3048)
			(stroke
				(width 0.1)
				(type default)
			)
			(layer "F.Fab")
		)
		(fp_line
			(start 0.120396 0.3048)
			(end 0.120396 0.2794)
			(stroke
				(width 0.1)
				(type default)
			)
			(layer "F.Fab")
		)
		(fp_line
			(start 0.67945 0.3048)
			(end 0.120396 0.3048)
			(stroke
				(width 0.1)
				(type default)
			)
			(layer "F.Fab")
		)
		(fp_line
			(start -0.12065 0.2794)
			(end -0.12065 0.3048)
			(stroke
				(width 0.1)
				(type default)
			)
			(layer "F.Fab")
		)
		(fp_line
			(start 0.120396 0.2794)
			(end -0.12065 0.2794)
			(stroke
				(width 0.1)
				(type default)
			)
			(layer "F.Fab")
		)
		(fp_line
			(start -0.12065 -0.2794)
			(end 0.12065 -0.2794)
			(stroke
				(width 0.1)
				(type default)
			)
			(layer "F.Fab")
		)
		(fp_line
			(start 0.12065 -0.2794)
			(end 0.12065 -0.3048)
			(stroke
				(width 0.1)
				(type default)
			)
			(layer "F.Fab")
		)
		(fp_line
			(start 0.12065 -0.3048)
			(end 0.67945 -0.3048)
			(stroke
				(width 0.1)
				(type default)
			)
			(layer "F.Fab")
		)
		(fp_line
			(start 0.67945 -0.3048)
			(end 0.67945 0.3048)
			(stroke
				(width 0.1)
				(type default)
			)
			(layer "F.Fab")
		)
		(fp_line
			(start -0.67945 -0.305054)
			(end -0.12065 -0.305054)
			(stroke
				(width 0.1)
				(type default)
			)
			(layer "F.Fab")
		)
		(fp_line
			(start -0.12065 -0.305054)
			(end -0.12065 -0.2794)
			(stroke
				(width 0.1)
				(type default)
			)
			(layer "F.Fab")
		)
		(pad "1" smd circle
			(at -0.40005 0 270)
			(size 0 0)
			(layers "F.Cu" "F.Mask" "F.Paste")
			(net "P3V3_AUX")
		)
		(pad "2" smd circle
			(at 0.40005 0 270)
			(size 0 0)
			(layers "F.Cu" "F.Mask" "F.Paste")
			(net "SSD6_AUX_P3V3_EN")
		)
	)
	(footprint ""
		(layer "F.Cu")
		(at 458.818234 -274.8915 180)
		(property "Reference" "R810"
			(at 0 0 180)
			(layer "F.SilkS")
			(hide yes)
			(effects
				(font
					(size 1.27 1.27)
				)
			)
		)
		(property "Value" ""
			(at 0 0 180)
			(layer "F.Fab")
			(effects
				(font
					(size 1.27 1.27)
				)
			)
		)
		(duplicate_pad_numbers_are_jumpers no)
		(fp_line
			(start 0.7874 0.4064)
			(end -0.7874 0.4064)
			(stroke
				(width 0.1524)
				(type default)
			)
			(layer "F.SilkS")
		)
		(fp_line
			(start 0.7874 -0.4064)
			(end 0.7874 0.4064)
			(stroke
				(width 0.1524)
				(type default)
			)
			(layer "F.SilkS")
		)
		(fp_line
			(start -0.7874 0.4064)
			(end -0.7874 -0.4064)
			(stroke
				(width 0.1524)
				(type default)
			)
			(layer "F.SilkS")
		)
		(fp_line
			(start -0.7874 -0.4064)
			(end 0.7874 -0.4064)
			(stroke
				(width 0.1524)
				(type default)
			)
			(layer "F.SilkS")
		)
		(fp_line
			(start 0.67945 0.3048)
			(end 0.120396 0.3048)
			(stroke
				(width 0.1)
				(type default)
			)
			(layer "F.Fab")
		)
		(fp_line
			(start 0.67945 -0.3048)
			(end 0.67945 0.3048)
			(stroke
				(width 0.1)
				(type default)
			)
			(layer "F.Fab")
		)
		(fp_line
			(start 0.12065 -0.2794)
			(end 0.12065 -0.3048)
			(stroke
				(width 0.1)
				(type default)
			)
			(layer "F.Fab")
		)
		(fp_line
			(start 0.12065 -0.3048)
			(end 0.67945 -0.3048)
			(stroke
				(width 0.1)
				(type default)
			)
			(layer "F.Fab")
		)
		(fp_line
			(start 0.120396 0.3048)
			(end 0.120396 0.2794)
			(stroke
				(width 0.1)
				(type default)
			)
			(layer "F.Fab")
		)
		(fp_line
			(start 0.120396 0.2794)
			(end -0.12065 0.2794)
			(stroke
				(width 0.1)
				(type default)
			)
			(layer "F.Fab")
		)
		(fp_line
			(start -0.12065 0.3048)
			(end -0.67945 0.3048)
			(stroke
				(width 0.1)
				(type default)
			)
			(layer "F.Fab")
		)
		(fp_line
			(start -0.12065 0.2794)
			(end -0.12065 0.3048)
			(stroke
				(width 0.1)
				(type default)
			)
			(layer "F.Fab")
		)
		(fp_line
			(start -0.12065 -0.2794)
			(end 0.12065 -0.2794)
			(stroke
				(width 0.1)
				(type default)
			)
			(layer "F.Fab")
		)
		(fp_line
			(start -0.12065 -0.305054)
			(end -0.12065 -0.2794)
			(stroke
				(width 0.1)
				(type default)
			)
			(layer "F.Fab")
		)
		(fp_line
			(start -0.67945 0.3048)
			(end -0.67945 -0.305054)
			(stroke
				(width 0.1)
				(type default)
			)
			(layer "F.Fab")
		)
		(fp_line
			(start -0.67945 -0.305054)
			(end -0.12065 -0.305054)
			(stroke
				(width 0.1)
				(type default)
			)
			(layer "F.Fab")
		)
		(pad "1" smd circle
			(at -0.40005 0 180)
			(size 0 0)
			(layers "F.Cu" "F.Mask" "F.Paste")
			(net "P1V25_PEX3_R")
		)
		(pad "2" smd circle
			(at 0.40005 0 180)
			(size 0 0)
			(layers "F.Cu" "F.Mask" "F.Paste")
			(net "P12V_PEX3_P1V25_VIN_P")
		)
	)
	(footprint ""
		(layer "F.Cu")
		(at 104.243632 -48.93691 180)
		(property "Reference" "R545"
			(at 0 0 180)
			(layer "F.SilkS")
			(hide yes)
			(effects
				(font
					(size 1.27 1.27)
				)
			)
		)
		(property "Value" ""
			(at 0 0 180)
			(layer "F.Fab")
			(effects
				(font
					(size 1.27 1.27)
				)
			)
		)
		(duplicate_pad_numbers_are_jumpers no)
		(fp_line
			(start 0.7874 0.4064)
			(end -0.7874 0.4064)
			(stroke
				(width 0.1524)
				(type default)
			)
			(layer "F.SilkS")
		)
		(fp_line
			(start 0.7874 -0.4064)
			(end 0.7874 0.4064)
			(stroke
				(width 0.1524)
				(type default)
			)
			(layer "F.SilkS")
		)
		(fp_line
			(start -0.7874 0.4064)
			(end -0.7874 -0.4064)
			(stroke
				(width 0.1524)
				(type default)
			)
			(layer "F.SilkS")
		)
		(fp_line
			(start -0.7874 -0.4064)
			(end 0.7874 -0.4064)
			(stroke
				(width 0.1524)
				(type default)
			)
			(layer "F.SilkS")
		)
		(fp_line
			(start 0.67945 0.3048)
			(end 0.120396 0.3048)
			(stroke
				(width 0.1)
				(type default)
			)
			(layer "F.Fab")
		)
		(fp_line
			(start 0.67945 -0.3048)
			(end 0.67945 0.3048)
			(stroke
				(width 0.1)
				(type default)
			)
			(layer "F.Fab")
		)
		(fp_line
			(start 0.12065 -0.2794)
			(end 0.12065 -0.3048)
			(stroke
				(width 0.1)
				(type default)
			)
			(layer "F.Fab")
		)
		(fp_line
			(start 0.12065 -0.3048)
			(end 0.67945 -0.3048)
			(stroke
				(width 0.1)
				(type default)
			)
			(layer "F.Fab")
		)
		(fp_line
			(start 0.120396 0.3048)
			(end 0.120396 0.2794)
			(stroke
				(width 0.1)
				(type default)
			)
			(layer "F.Fab")
		)
		(fp_line
			(start 0.120396 0.2794)
			(end -0.12065 0.2794)
			(stroke
				(width 0.1)
				(type default)
			)
			(layer "F.Fab")
		)
		(fp_line
			(start -0.12065 0.3048)
			(end -0.67945 0.3048)
			(stroke
				(width 0.1)
				(type default)
			)
			(layer "F.Fab")
		)
		(fp_line
			(start -0.12065 0.2794)
			(end -0.12065 0.3048)
			(stroke
				(width 0.1)
				(type default)
			)
			(layer "F.Fab")
		)
		(fp_line
			(start -0.12065 -0.2794)
			(end 0.12065 -0.2794)
			(stroke
				(width 0.1)
				(type default)
			)
			(layer "F.Fab")
		)
		(fp_line
			(start -0.12065 -0.305054)
			(end -0.12065 -0.2794)
			(stroke
				(width 0.1)
				(type default)
			)
			(layer "F.Fab")
		)
		(fp_line
			(start -0.67945 0.3048)
			(end -0.67945 -0.305054)
			(stroke
				(width 0.1)
				(type default)
			)
			(layer "F.Fab")
		)
		(fp_line
			(start -0.67945 -0.305054)
			(end -0.12065 -0.305054)
			(stroke
				(width 0.1)
				(type default)
			)
			(layer "F.Fab")
		)
		(pad "1" smd circle
			(at -0.40005 0 180)
			(size 0 0)
			(layers "F.Cu" "F.Mask" "F.Paste")
			(net "SMB_BIC_I2C6_MUX_SSD_0_7_ADC_R_SDA")
		)
		(pad "2" smd circle
			(at 0.40005 0 180)
			(size 0 0)
			(layers "F.Cu" "F.Mask" "F.Paste")
			(net "SMB_SSD3_ADC_SDA")
		)
	)
	(footprint ""
		(layer "F.Cu")
		(at 377.842018 -305.648106 -135)
		(property "Reference" "R1444"
			(at 0 0 225)
			(layer "F.SilkS")
			(hide yes)
			(effects
				(font
					(size 1.27 1.27)
				)
			)
		)
		(property "Value" ""
			(at 0 0 225)
			(layer "F.Fab")
			(effects
				(font
					(size 1.27 1.27)
				)
			)
		)
		(duplicate_pad_numbers_are_jumpers no)
		(fp_line
			(start 0.787389 0.406267)
			(end -0.787389 0.406267)
			(stroke
				(width 0.1524)
				(type default)
			)
			(layer "F.SilkS")
		)
		(fp_line
			(start 0.787389 -0.406267)
			(end 0.787389 0.406267)
			(stroke
				(width 0.1524)
				(type default)
			)
			(layer "F.SilkS")
		)
		(fp_line
			(start -0.787389 0.406267)
			(end -0.787389 -0.406267)
			(stroke
				(width 0.1524)
				(type default)
			)
			(layer "F.SilkS")
		)
		(fp_line
			(start -0.787389 -0.406267)
			(end 0.787389 -0.406267)
			(stroke
				(width 0.1524)
				(type default)
			)
			(layer "F.SilkS")
		)
		(fp_line
			(start 0.679446 0.30479)
			(end 0.120515 0.30479)
			(stroke
				(width 0.1)
				(type default)
			)
			(layer "F.Fab")
		)
		(fp_line
			(start 0.120515 0.30479)
			(end 0.120335 0.279466)
			(stroke
				(width 0.1)
				(type default)
			)
			(layer "F.Fab")
		)
		(fp_line
			(start 0.120335 0.279466)
			(end -0.120695 0.279466)
			(stroke
				(width 0.1)
				(type default)
			)
			(layer "F.Fab")
		)
		(fp_line
			(start 0.679446 -0.30479)
			(end 0.679446 0.30479)
			(stroke
				(width 0.1)
				(type default)
			)
			(layer "F.Fab")
		)
		(fp_line
			(start -0.120515 0.30479)
			(end -0.679446 0.30479)
			(stroke
				(width 0.1)
				(type default)
			)
			(layer "F.Fab")
		)
		(fp_line
			(start -0.120695 0.279466)
			(end -0.120515 0.30479)
			(stroke
				(width 0.1)
				(type default)
			)
			(layer "F.Fab")
		)
		(fp_line
			(start 0.120695 -0.279466)
			(end 0.120515 -0.30479)
			(stroke
				(width 0.1)
				(type default)
			)
			(layer "F.Fab")
		)
		(fp_line
			(start 0.120515 -0.30479)
			(end 0.679446 -0.30479)
			(stroke
				(width 0.1)
				(type default)
			)
			(layer "F.Fab")
		)
		(fp_line
			(start -0.679446 0.30479)
			(end -0.679446 -0.305149)
			(stroke
				(width 0.1)
				(type default)
			)
			(layer "F.Fab")
		)
		(fp_line
			(start -0.120695 -0.279466)
			(end 0.120695 -0.279466)
			(stroke
				(width 0.1)
				(type default)
			)
			(layer "F.Fab")
		)
		(fp_line
			(start -0.120695 -0.304969)
			(end -0.120695 -0.279466)
			(stroke
				(width 0.1)
				(type default)
			)
			(layer "F.Fab")
		)
		(fp_line
			(start -0.679446 -0.305149)
			(end -0.120695 -0.304969)
			(stroke
				(width 0.1)
				(type default)
			)
			(layer "F.Fab")
		)
		(pad "1" smd circle
			(at -0.40005 0 225)
			(size 0 0)
			(layers "F.Cu" "F.Mask" "F.Paste")
			(net "PEX3_DFT_IDDT")
		)
		(pad "2" smd circle
			(at 0.40005 0 225)
			(size 0 0)
			(layers "F.Cu" "F.Mask" "F.Paste")
			(net "P1V8_PEX")
		)
	)
)
